FILE_TYPE = CONNECTIVITY;
{Allegro Design Entry HDL 17.4-2019 S026 (4007227) 1/17/2022}
"PAGE_NUMBER" = 158;
0"NC";
1"GND\g";
2"GND\g";
3"GND\g";
4"GND\g";
5"GND\g";
6"GND\g";
7"GND\g";
8"GND\g";
9"USB3_CPU0_BMC_TX_C2_DP";
10"USB3_CPU0_BMC_TX_C2_DN";
11"USB2_CPU0_P0_R2_DP";
12"USB2_CPU0_P0_R2_DN";
13"USB2_CPU0_P0_DN";
14"USB2_CPU0_P0_DP";
15"USB3_CPU0_BMC_TX_BUF_C_DP";
16"USB3_CPU0_BMC_TX_BUF_C_DN";
17"USB3_CPU0_BMC_RX_C1_DN";
18"USB3_CPU0_BMC_RX_C2_DN";
19"USB3_CPU0_BMC_RX_C1_DP";
20"USB3_CPU0_BMC_RX_C2_DP";
21"USB3_CPU0_BMC_TX_DN";
22"USB3_CPU0_BMC_TX_DP";
23"USB3_CPU0_BMC_TX_C1_DN";
24"USB3_CPU0_BMC_TX_C1_DP";
25"USB2_CPU0_P0_R1_DN";
26"USB2_CPU0_P0_R1_DP";
27"USB3_CPU0_BMC_RX_HUB1_DP";
28"USB3_CPU0_BMC_RX_HUB_C_DP";
29"USB3_CPU0_BMC_RX_HUB_C_DN";
30"USB3_CPU0_BMC_RX_HUB2_DP";
31"USB3_CPU0_BMC_RX_HUB2_DN";
32"USB3_CPU0_BMC_RX_HUB1_DN";
33"USB3_CPU0_BMC_HUB2_TX_DP";
34"USB3_CPU0_BMC_HUB2_TX_DN";
35"USB3_CPU0_BMC_HUB1_TX_DN";
36"USB3_CPU0_BMC_HUB1_TX_DP";
37"USB2_HUB_EXT_DN";
38"USB2_HUB_EXT_DP";
39"USB2_CPU0_P0_HUB2_R_DN";
40"USB2_CPU0_P0_HUB2_R_DP";
41"USB2_CPU0_P0_HUB1_R_DN";
42"USB2_CPU0_P0_HUB1_R_DP";
43"USB3_CPU0_BMC_RX_DN";
44"USB3_CPU0_BMC_RX_DP";
%"GND"
"1","(-8750,5300)","0","pure_quanta_power","I105";
;
SIZE"1B"
CDS_LIB"pure_quanta_power"
HDL_POWER"GND";
"A<SIZE-1..0>\NAC"1;
%"GND"
"1","(-8675,5300)","0","pure_quanta_power","I106";
;
CDS_LIB"pure_quanta_power"
SIZE"1B"
HDL_POWER"GND";
"A<SIZE-1..0>\NAC"2;
%"GND"
"1","(-8575,4050)","0","pure_quanta_power","I107";
;
SIZE"1B"
CDS_LIB"pure_quanta_power"
HDL_POWER"GND";
"A<SIZE-1..0>\NAC"3;
%"GND"
"1","(-8650,4050)","0","pure_quanta_power","I110";
;
SIZE"1B"
CDS_LIB"pure_quanta_power"
HDL_POWER"GND";
"A<SIZE-1..0>\NAC"4;
%"GND"
"1","(-6075,5050)","0","pure_quanta_power","I113";
;
CDS_LIB"pure_quanta_power"
SIZE"1B"
HDL_POWER"GND";
"A<SIZE-1..0>\NAC"5;
%"GND"
"1","(-6150,5050)","0","pure_quanta_power","I114";
;
CDS_LIB"pure_quanta_power"
SIZE"1B"
HDL_POWER"GND";
"A<SIZE-1..0>\NAC"6;
%"GND"
"1","(-6150,3700)","0","pure_quanta_power","I117";
;
CDS_LIB"pure_quanta_power"
SIZE"1B"
HDL_POWER"GND";
"A<SIZE-1..0>\NAC"7;
%"GND"
"1","(-6075,3700)","0","pure_quanta_power","I118";
;
CDS_LIB"pure_quanta_power"
SIZE"1B"
HDL_POWER"GND";
"A<SIZE-1..0>\NAC"8;
%"Q_RES"
"2","(-8750,5650)","2","pure_quanta","I120";
;
LOCATION"R339"
$SEC"1"
CDS_SEC"1"
VALUE"49.9"
TOLERANCE"1%"
MATERIAL"EMPTY"
WATTAGE"1/20W"
PACK_TYPE"0201LF"
CDS_LIB"pure_quanta"
PART_NUMBER"CS04991FE06";
"A"
$PN"1"14;
"B"
$PN"2"1;
%"Q_RES"
"2","(-8675,5650)","0","pure_quanta","I121";
;
LOCATION"R340"
$SEC"1"
CDS_SEC"1"
MATERIAL"EMPTY"
TOLERANCE"1%"
PACK_TYPE"0201LF"
WATTAGE"1/20W"
VALUE"49.9"
CDS_LIB"pure_quanta"
PART_NUMBER"CS04991FE06";
"A"
$PN"1"13;
"B"
$PN"2"2;
%"Q_RES"
"2","(-6075,5400)","0","pure_quanta","I124";
;
LOCATION"R345"
$SEC"1"
CDS_SEC"1"
VALUE"49.9"
PACK_TYPE"0201LF"
MATERIAL"EMPTY"
WATTAGE"1/20W"
TOLERANCE"1%"
CDS_LIB"pure_quanta"
PART_NUMBER"CS04991FE06";
"A"
$PN"1"12;
"B"
$PN"2"5;
%"Q_RES"
"2","(-6150,5400)","2","pure_quanta","I125";
;
LOCATION"R343"
$SEC"1"
CDS_SEC"1"
TOLERANCE"1%"
MATERIAL"EMPTY"
WATTAGE"1/20W"
PACK_TYPE"0201LF"
VALUE"49.9"
CDS_LIB"pure_quanta"
PART_NUMBER"CS04991FE06";
"A"
$PN"1"11;
"B"
$PN"2"6;
%"Q_RES"
"2","(-6075,4050)","0","pure_quanta","I126";
;
LOCATION"R346"
$SEC"1"
CDS_SEC"1"
TOLERANCE"1%"
PACK_TYPE"0201LF"
VALUE"49.9"
MATERIAL"EMPTY"
WATTAGE"1/20W"
CDS_LIB"pure_quanta"
PART_NUMBER"CS04991FE06";
"A"
$PN"1"10;
"B"
$PN"2"8;
%"Q_RES"
"2","(-6150,4050)","2","pure_quanta","I127";
;
LOCATION"R344"
$SEC"1"
CDS_SEC"1"
VALUE"49.9"
PACK_TYPE"0201LF"
MATERIAL"EMPTY"
WATTAGE"1/20W"
TOLERANCE"1%"
CDS_LIB"pure_quanta"
PART_NUMBER"CS04991FE06";
"A"
$PN"1"9;
"B"
$PN"2"7;
%"Q_CAP"
"2","(-3150,4550)","0","pure_quanta","I137";
;
LOCATION"C6023"
$SEC"1"
CDS_SEC"1"
ROOM"USB3_HUB1"
CDS_LIB"pure_quanta"
VOLTAGE"25V"
VALUE"0.1UF"
TOLERANCE"10%"
PACK_TYPE"0402"
MATERIAL"X7R"
PART_NUMBER"CH4104K1B00";
"A"
$PN"1"36;
"B"
$PN"2"15;
%"Q_CAP"
"2","(-3150,4500)","0","pure_quanta","I138";
;
LOCATION"C6024"
$SEC"1"
CDS_SEC"1"
VALUE"0.1UF"
VOLTAGE"25V"
MATERIAL"X7R"
PACK_TYPE"0402"
ROOM"USB3_HUB1"
TOLERANCE"10%"
CDS_LIB"pure_quanta"
PART_NUMBER"CH4104K1B00";
"A"
$PN"1"35;
"B"
$PN"2"16;
%"Q_CAP"
"2","(-3125,3975)","0","pure_quanta","I139";
;
LOCATION"C6025"
$SEC"1"
CDS_SEC"1"
ROOM"USB3_HUB2"
CDS_LIB"pure_quanta"
VOLTAGE"25V"
VALUE"0.1UF"
TOLERANCE"10%"
PACK_TYPE"0402"
MATERIAL"X7R"
PART_NUMBER"CH4104K1B00";
"A"
$PN"1"33;
"B"
$PN"2"15;
%"Q_CAP"
"2","(-3125,3925)","0","pure_quanta","I140";
;
LOCATION"C6026"
$SEC"1"
CDS_SEC"1"
VALUE"0.1UF"
VOLTAGE"25V"
ROOM"USB3_HUB2"
CDS_LIB"pure_quanta"
TOLERANCE"10%"
PACK_TYPE"0402"
MATERIAL"X7R"
PART_NUMBER"CH4104K1B00";
"A"
$PN"1"34;
"B"
$PN"2"16;
%"Q_CAP"
"2","(-7575,4400)","0","pure_quanta","I141";
;
LOCATION"C6014"
$SEC"1"
CDS_SEC"1"
VALUE"0.1UF"
VOLTAGE"25V"
ROOM"USB3_HUB2"
TOLERANCE"10%"
PACK_TYPE"0402"
MATERIAL"X7R"
CDS_LIB"pure_quanta"
PART_NUMBER"CH4104K1B00";
"A"
$PN"1"21;
"B"
$PN"2"10;
%"Q_CAP"
"2","(-7575,4450)","0","pure_quanta","I142";
;
LOCATION"C6013"
$SEC"1"
CDS_SEC"1"
ROOM"USB3_HUB2"
VOLTAGE"25V"
VALUE"0.1UF"
TOLERANCE"10%"
PACK_TYPE"0402"
MATERIAL"X7R"
CDS_LIB"pure_quanta"
PART_NUMBER"CH4104K1B00";
"A"
$PN"1"22;
"B"
$PN"2"9;
%"Q_CAP"
"2","(-7575,4750)","0","pure_quanta","I143";
;
LOCATION"C6004"
$SEC"1"
CDS_SEC"1"
ROOM"USB3_HUB1"
TOLERANCE"10%"
MATERIAL"X7R"
VOLTAGE"25V"
VALUE"0.1UF"
PACK_TYPE"0402"
CDS_LIB"pure_quanta"
PART_NUMBER"CH4104K1B00";
"A"
$PN"1"21;
"B"
$PN"2"23;
%"Q_CAP"
"2","(-7575,4800)","0","pure_quanta","I144";
;
LOCATION"C6003"
$SEC"1"
CDS_SEC"1"
ROOM"USB3_HUB1"
VOLTAGE"25V"
VALUE"0.1UF"
TOLERANCE"10%"
PACK_TYPE"0402"
MATERIAL"X7R"
CDS_LIB"pure_quanta"
PART_NUMBER"CH4104K1B00";
"A"
$PN"1"22;
"B"
$PN"2"24;
%"Q_RES"
"2","(-8650,4400)","2","pure_quanta","I145";
;
LOCATION"R341"
$SEC"1"
CDS_SEC"1"
VALUE"51"
TOLERANCE"5%"
MATERIAL"EMPTY"
WATTAGE"1/16W"
PACK_TYPE"0402LF"
CDS_LIB"pure_quanta"
PART_NUMBER"CS05102JB04";
"A"
$PN"1"22;
"B"
$PN"2"4;
%"Q_RES"
"2","(-8575,4425)","0","pure_quanta","I146";
;
LOCATION"R342"
$SEC"1"
CDS_SEC"1"
TOLERANCE"5%"
MATERIAL"EMPTY"
WATTAGE"1/16W"
VALUE"51"
PACK_TYPE"0402LF"
CDS_LIB"pure_quanta"
PART_NUMBER"CS05102JB04";
"A"
$PN"1"21;
"B"
$PN"2"3;
%"Q_CAP"
"2","(-3125,2100)","0","pure_quanta","I147";
;
LOCATION"C6018"
$SEC"1"
CDS_SEC"1"
VOLTAGE"25V"
MATERIAL"X7R"
ROOM"USB3_HUB2"
TOLERANCE"10%"
PACK_TYPE"0402"
VALUE"0.1UF"
CDS_LIB"pure_quanta"
PART_NUMBER"CH4104K1B00";
"A"
$PN"1"31;
"B"
$PN"2"29;
%"Q_CAP"
"2","(-3125,2150)","0","pure_quanta","I148";
;
LOCATION"C6017"
$SEC"1"
CDS_SEC"1"
ROOM"USB3_HUB2"
CDS_LIB"pure_quanta"
MATERIAL"X7R"
PACK_TYPE"0402"
TOLERANCE"10%"
VALUE"0.1UF"
VOLTAGE"25V"
PART_NUMBER"CH4104K1B00";
"A"
$PN"1"30;
"B"
$PN"2"28;
%"Q_RES"
"1","(-7525,5650)","0","pure_quanta","I3";
;
LOCATION"R6192"
$SEC"1"
CDS_SEC"1"
ROOM"USB3_HUB2"
PACK_TYPE"0201LF"
VALUE"0"
MATERIAL"CHIP"
CDS_LIB"pure_quanta"
TOLERANCE"5%"
WATTAGE"1/20W"
PART_NUMBER"CS00001JE10";
"B"
$PN"2"11;
"A"
$PN"1"14;
%"Q_RES"
"1","(-7525,5600)","0","pure_quanta","I4";
;
LOCATION"R6193"
$SEC"1"
CDS_SEC"1"
ROOM"USB3_HUB2"
MATERIAL"CHIP"
VALUE"0"
PACK_TYPE"0201LF"
CDS_LIB"pure_quanta"
WATTAGE"1/20W"
TOLERANCE"5%"
PART_NUMBER"CS00001JE10";
"B"
$PN"2"12;
"A"
$PN"1"13;
%"Q_CAP_DIFFBUS"
"2","(-3175,2725)","0","pure_quanta","I49";
;
LOCATION"C6015"
$SEC"1"
CDS_SEC"1"
ROOM"USB3_HUB1"
MATERIAL"X6S"
PACK_TYPE"C0402"
TOLERANCE"10%"
VOLTAGE"6.3V"
VALUE"DIFF BUS_0.33UF"
PIN_NAMES_ROTATE"True"
CDS_LIB"pure_quanta"
CDS_LMAN_SYM_OUTLINE"-25,50,25,-50"
PART_NUMBER"SP_CH4331KEB01";
"2"
$PN"2"28;
"1"
$PN"1"27;
%"Q_RES"
"1","(-7550,5950)","0","pure_quanta","I5";
;
LOCATION"R6191"
$SEC"1"
CDS_SEC"1"
ROOM"USB3_HUB1"
VALUE"0"
MATERIAL"CHIP"
PACK_TYPE"0201LF"
TOLERANCE"5%"
WATTAGE"1/20W"
CDS_LIB"pure_quanta"
PART_NUMBER"CS00001JE10";
"B"
$PN"2"25;
"A"
$PN"1"13;
%"Q_CAP_DIFFBUS"
"2","(-3175,2675)","0","pure_quanta","I50";
;
LOCATION"C6016"
$SEC"1"
CDS_SEC"1"
ROOM"USB3_HUB1"
VALUE"DIFF BUS_0.33UF"
CDS_LIB"pure_quanta"
CDS_LMAN_SYM_OUTLINE"-25,50,25,-50"
TOLERANCE"10%"
VOLTAGE"6.3V"
MATERIAL"X6S"
PACK_TYPE"C0402"
PIN_NAMES_ROTATE"True"
PART_NUMBER"SP_CH4331KEB01";
"2"
$PN"2"29;
"1"
$PN"1"32;
%"Q_RES"
"1","(-7550,6000)","0","pure_quanta","I6";
;
LOCATION"R6190"
$SEC"1"
CDS_SEC"1"
MATERIAL"CHIP"
ROOM"USB3_HUB1"
WATTAGE"1/20W"
VALUE"0"
TOLERANCE"5%"
PACK_TYPE"0201LF"
CDS_LIB"pure_quanta"
PART_NUMBER"CS00001JE10";
"B"
$PN"2"26;
"A"
$PN"1"14;
%"Q_RES"
"1","(-2975,5950)","0","pure_quanta","I71";
;
LOCATION"R6195"
$SEC"1"
CDS_SEC"1"
MATERIAL"CHIP"
PACK_TYPE"0201LF"
VALUE"0"
ROOM"USB3_HUB1"
WATTAGE"1/20W"
TOLERANCE"5%"
CDS_LIB"pure_quanta"
PART_NUMBER"CS00001JE10";
"B"
$PN"2"37;
"A"
$PN"1"41;
%"Q_RES"
"1","(-2975,6000)","0","pure_quanta","I72";
;
LOCATION"R6194"
$SEC"1"
CDS_SEC"1"
PACK_TYPE"0201LF"
TOLERANCE"5%"
VALUE"0"
WATTAGE"1/20W"
MATERIAL"CHIP"
ROOM"USB3_HUB1"
CDS_LIB"pure_quanta"
PART_NUMBER"CS00001JE10";
"B"
$PN"2"38;
"A"
$PN"1"42;
%"Q_RES"
"1","(-2950,5425)","0","pure_quanta","I73";
;
LOCATION"R6196"
$SEC"1"
CDS_SEC"1"
MATERIAL"CHIP"
VALUE"0"
PACK_TYPE"0201LF"
ROOM"USB3_HUB2"
WATTAGE"1/20W"
TOLERANCE"5%"
CDS_LIB"pure_quanta"
PART_NUMBER"CS00001JE10";
"B"
$PN"2"38;
"A"
$PN"1"40;
%"Q_RES"
"1","(-2950,5375)","0","pure_quanta","I74";
;
LOCATION"R6197"
$SEC"1"
CDS_SEC"1"
VALUE"0"
PACK_TYPE"0201LF"
MATERIAL"CHIP"
ROOM"USB3_HUB2"
TOLERANCE"5%"
WATTAGE"1/20W"
CDS_LIB"pure_quanta"
PART_NUMBER"CS00001JE10";
"B"
$PN"2"37;
"A"
$PN"1"39;
%"Q_CAP_DIFFBUS"
"2","(-7300,2650)","0","pure_quanta","I85";
;
LOCATION"C6019"
$SEC"1"
CDS_SEC"1"
MATERIAL"X6S"
VOLTAGE"6.3V"
PACK_TYPE"C0402"
ROOM"USB3_HUB1"
TOLERANCE"10%"
VALUE"DIFF BUS_0.33UF"
PIN_NAMES_ROTATE"True"
CDS_LMAN_SYM_OUTLINE"-25,50,25,-50"
CDS_LIB"pure_quanta"
PART_NUMBER"SP_CH4331KEB01";
"2"
$PN"2"19;
"1"
$PN"1"44;
%"Q_CAP_DIFFBUS"
"2","(-7300,2600)","0","pure_quanta","I86";
;
LOCATION"C6020"
$SEC"1"
CDS_SEC"1"
ROOM"USB3_HUB1"
VALUE"DIFF BUS_0.33UF"
TOLERANCE"10%"
VOLTAGE"6.3V"
MATERIAL"X6S"
PACK_TYPE"C0402"
PIN_NAMES_ROTATE"True"
CDS_LIB"pure_quanta"
CDS_LMAN_SYM_OUTLINE"-25,50,25,-50"
PART_NUMBER"SP_CH4331KEB01";
"2"
$PN"2"17;
"1"
$PN"1"43;
%"Q_CAP_DIFFBUS"
"2","(-7300,2300)","0","pure_quanta","I87";
;
LOCATION"C6021"
$SEC"1"
CDS_SEC"1"
ROOM"USB3_HUB2"
VALUE"DIFF BUS_0.33UF"
PIN_NAMES_ROTATE"True"
PACK_TYPE"C0402"
MATERIAL"X6S"
VOLTAGE"6.3V"
TOLERANCE"10%"
CDS_LMAN_SYM_OUTLINE"-25,50,25,-50"
CDS_LIB"pure_quanta"
PART_NUMBER"SP_CH4331KEB01";
"2"
$PN"2"20;
"1"
$PN"1"44;
%"Q_CAP_DIFFBUS"
"2","(-7300,2250)","0","pure_quanta","I88";
;
LOCATION"C6022"
$SEC"1"
CDS_SEC"1"
ROOM"USB3_HUB2"
VALUE"DIFF BUS_0.33UF"
TOLERANCE"10%"
VOLTAGE"6.3V"
MATERIAL"X6S"
PACK_TYPE"C0402"
PIN_NAMES_ROTATE"True"
CDS_LMAN_SYM_OUTLINE"-25,50,25,-50"
CDS_LIB"pure_quanta"
PART_NUMBER"SP_CH4331KEB01";
"2"
$PN"2"18;
"1"
$PN"1"43;
END.
